# T6G (Grand Teton) — schematic netlist excerpt (pin names and nets, part order shuffled) for the footprints in the layout excerpt that follows; sources: Cadence DE-HDL packaged netlist, KiCad conversion of 04192023_DAF0TMB3IC0_F0TG_MB_C_brd_V02_OCP.brd

R1039  Q_RES  4.7K 5% CHIP  pkg 0201LF  page 287 : A = P1V8_CPU0_RT_1D ; B = MODE_RT_CPU0_P1
C9001  Q_CAP  1000PF 50V 5% EMPTY  pkg 0402  page 123 : A = PRSNT_CABLE_SWB_B2_ISO_N ; B = GND
PC363  Q_CAP  1UF 6.3V 10% X7R  pkg 0402  page 217 : A = PVDD18_S5_P1 ; B = GND

(kicad_pcb
	(version 20260206)
	(generator "pcbnew")
	(generator_version "10.0")
	(general
		(thickness 1.6)
		(legacy_teardrops no)
	)
	(paper "A4")
	(title_block
		(title "04192023_DAF0TMB3IC0_F0TG_MB_C_brd_V02_OCP.brd")
		(comment 1 "Grand Teton / footprints 1997-1999 of 8354")
	)
	(layers
		(0 "F.Cu" signal "TOP")
		(4 "In1.Cu" signal "GND")
		(6 "In2.Cu" signal "IN1")
		(8 "In3.Cu" signal "GND1")
		(10 "In4.Cu" signal "IN2")
		(12 "In5.Cu" signal "GND2")
		(14 "In6.Cu" signal "IN3")
		(16 "In7.Cu" signal "GND3")
		(18 "In8.Cu" signal "VCC")
		(20 "In9.Cu" signal "VCC1")
		(22 "In10.Cu" signal "GND4")
		(24 "In11.Cu" signal "IN4")
		(26 "In12.Cu" signal "GND5")
		(28 "In13.Cu" signal "IN5")
		(30 "In14.Cu" signal "GND6")
		(32 "In15.Cu" signal "IN6")
		(34 "In16.Cu" signal "GND7")
		(2 "B.Cu" signal "BOTTOM")
		(9 "F.Adhes" user "F.Adhesive")
		(11 "B.Adhes" user "B.Adhesive")
		(13 "F.Paste" user "Package Geometry/Pastemask Top")
		(15 "B.Paste" user "Package Geometry/Pastemask Bottom")
		(5 "F.SilkS" user "Ref Des/Silkscreen Top")
		(7 "B.SilkS" user "Ref Des/Silkscreen Bottom")
		(1 "F.Mask" user "Board Geometry/Soldermask Top")
		(3 "B.Mask" user "Board Geometry/Soldermask Bottom")
		(17 "Dwgs.User" user "User.Drawings")
		(19 "Cmts.User" user "User.Comments")
		(21 "Eco1.User" user "User.Eco1")
		(23 "Eco2.User" user "User.Eco2")
		(25 "Edge.Cuts" user "Board Geometry/Outline")
		(27 "Margin" user)
		(31 "F.CrtYd" user "Package Geometry/Place Bound Top")
		(29 "B.CrtYd" user "Package Geometry/Place Bound Bottom")
		(35 "F.Fab" user "Ref Des/Assembly Top")
		(33 "B.Fab" user "Ref Des/Assembly Bottom")
	)
	(footprint ""
		(layer "F.Cu")
		(at 172.54347 -415.503868 180)
		(property "Reference" "C9001"
			(at 0 0 180)
			(layer "F.SilkS")
			(hide yes)
			(effects
				(font
					(size 1.27 1.27)
				)
			)
		)
		(property "Value" ""
			(at 0 0 180)
			(layer "F.Fab")
			(effects
				(font
					(size 1.27 1.27)
				)
			)
		)
		(duplicate_pad_numbers_are_jumpers no)
		(fp_line
			(start 0.7874 0.4064)
			(end -0.7874 0.4064)
			(stroke
				(width 0.1524)
				(type default)
			)
			(layer "F.SilkS")
		)
		(fp_line
			(start 0.7874 -0.4064)
			(end 0.7874 0.4064)
			(stroke
				(width 0.1524)
				(type default)
			)
			(layer "F.SilkS")
		)
		(fp_line
			(start -0.7874 0.4064)
			(end -0.7874 -0.4064)
			(stroke
				(width 0.1524)
				(type default)
			)
			(layer "F.SilkS")
		)
		(fp_line
			(start -0.7874 -0.4064)
			(end 0.7874 -0.4064)
			(stroke
				(width 0.1524)
				(type default)
			)
			(layer "F.SilkS")
		)
		(fp_line
			(start 0.67945 0.3048)
			(end 0.120396 0.3048)
			(stroke
				(width 0.1)
				(type default)
			)
			(layer "F.Fab")
		)
		(fp_line
			(start 0.67945 -0.3048)
			(end 0.67945 0.3048)
			(stroke
				(width 0.1)
				(type default)
			)
			(layer "F.Fab")
		)
		(fp_line
			(start 0.12065 -0.2794)
			(end 0.12065 -0.3048)
			(stroke
				(width 0.1)
				(type default)
			)
			(layer "F.Fab")
		)
		(fp_line
			(start 0.12065 -0.3048)
			(end 0.67945 -0.3048)
			(stroke
				(width 0.1)
				(type default)
			)
			(layer "F.Fab")
		)
		(fp_line
			(start 0.120396 0.3048)
			(end 0.120396 0.2794)
			(stroke
				(width 0.1)
				(type default)
			)
			(layer "F.Fab")
		)
		(fp_line
			(start 0.120396 0.2794)
			(end -0.12065 0.2794)
			(stroke
				(width 0.1)
				(type default)
			)
			(layer "F.Fab")
		)
		(fp_line
			(start -0.12065 0.3048)
			(end -0.67945 0.3048)
			(stroke
				(width 0.1)
				(type default)
			)
			(layer "F.Fab")
		)
		(fp_line
			(start -0.12065 0.2794)
			(end -0.12065 0.3048)
			(stroke
				(width 0.1)
				(type default)
			)
			(layer "F.Fab")
		)
		(fp_line
			(start -0.12065 -0.2794)
			(end 0.12065 -0.2794)
			(stroke
				(width 0.1)
				(type default)
			)
			(layer "F.Fab")
		)
		(fp_line
			(start -0.12065 -0.305054)
			(end -0.12065 -0.2794)
			(stroke
				(width 0.1)
				(type default)
			)
			(layer "F.Fab")
		)
		(fp_line
			(start -0.67945 0.3048)
			(end -0.67945 -0.305054)
			(stroke
				(width 0.1)
				(type default)
			)
			(layer "F.Fab")
		)
		(fp_line
			(start -0.67945 -0.305054)
			(end -0.12065 -0.305054)
			(stroke
				(width 0.1)
				(type default)
			)
			(layer "F.Fab")
		)
		(pad "1" smd circle
			(at -0.40005 0 180)
			(size 0 0)
			(layers "F.Cu" "F.Mask" "F.Paste")
			(net "PRSNT_CABLE_SWB_B2_ISO_N")
		)
		(pad "2" smd circle
			(at 0.40005 0 180)
			(size 0 0)
			(layers "F.Cu" "F.Mask" "F.Paste")
			(net "GND")
		)
	)
	(footprint ""
		(layer "F.Cu")
		(at 334.028288 -403.818852 -90)
		(property "Reference" "R1039"
			(at 0 0 270)
			(layer "F.SilkS")
			(hide yes)
			(effects
				(font
					(size 1.27 1.27)
				)
			)
		)
		(property "Value" ""
			(at 0 0 270)
			(layer "F.Fab")
			(effects
				(font
					(size 1.27 1.27)
				)
			)
		)
		(duplicate_pad_numbers_are_jumpers no)
		(fp_line
			(start -0.32512 0.175006)
			(end -0.32512 -0.175006)
			(stroke
				(width 0.1)
				(type default)
			)
			(layer "F.Fab")
		)
		(fp_line
			(start 0.32512 0.175006)
			(end -0.32512 0.175006)
			(stroke
				(width 0.1)
				(type default)
			)
			(layer "F.Fab")
		)
		(fp_line
			(start -0.32512 -0.175006)
			(end 0.32512 -0.175006)
			(stroke
				(width 0.1)
				(type default)
			)
			(layer "F.Fab")
		)
		(fp_line
			(start 0.32512 -0.175006)
			(end 0.32512 0.175006)
			(stroke
				(width 0.1)
				(type default)
			)
			(layer "F.Fab")
		)
		(pad "1" smd rect
			(at -0.2667 0 270)
			(size 0.3048 0.381)
			(layers "F.Cu" "F.Mask" "F.Paste")
			(net "P1V8_CPU0_RT_1D")
		)
		(pad "2" smd rect
			(at 0.2667 0 90)
			(size 0.3048 0.381)
			(layers "F.Cu" "F.Mask" "F.Paste")
			(net "MODE_RT_CPU0_P1")
		)
	)
	(footprint ""
		(layer "F.Cu")
		(at 24.765 -363.347 180)
		(property "Reference" "PC363"
			(at 0 0 180)
			(layer "F.SilkS")
			(hide yes)
			(effects
				(font
					(size 1.27 1.27)
				)
			)
		)
		(property "Value" ""
			(at 0 0 180)
			(layer "F.Fab")
			(effects
				(font
					(size 1.27 1.27)
				)
			)
		)
		(duplicate_pad_numbers_are_jumpers no)
		(fp_line
			(start 0.7874 0.4064)
			(end -0.7874 0.4064)
			(stroke
				(width 0.1524)
				(type default)
			)
			(layer "F.SilkS")
		)
		(fp_line
			(start 0.7874 -0.4064)
			(end 0.7874 0.4064)
			(stroke
				(width 0.1524)
				(type default)
			)
			(layer "F.SilkS")
		)
		(fp_line
			(start -0.7874 0.4064)
			(end -0.7874 -0.4064)
			(stroke
				(width 0.1524)
				(type default)
			)
			(layer "F.SilkS")
		)
		(fp_line
			(start -0.7874 -0.4064)
			(end 0.7874 -0.4064)
			(stroke
				(width 0.1524)
				(type default)
			)
			(layer "F.SilkS")
		)
		(fp_line
			(start 0.67945 0.3048)
			(end 0.120396 0.3048)
			(stroke
				(width 0.1)
				(type default)
			)
			(layer "F.Fab")
		)
		(fp_line
			(start 0.67945 -0.3048)
			(end 0.67945 0.3048)
			(stroke
				(width 0.1)
				(type default)
			)
			(layer "F.Fab")
		)
		(fp_line
			(start 0.12065 -0.2794)
			(end 0.12065 -0.3048)
			(stroke
				(width 0.1)
				(type default)
			)
			(layer "F.Fab")
		)
		(fp_line
			(start 0.12065 -0.3048)
			(end 0.67945 -0.3048)
			(stroke
				(width 0.1)
				(type default)
			)
			(layer "F.Fab")
		)
		(fp_line
			(start 0.120396 0.3048)
			(end 0.120396 0.2794)
			(stroke
				(width 0.1)
				(type default)
			)
			(layer "F.Fab")
		)
		(fp_line
			(start 0.120396 0.2794)
			(end -0.12065 0.2794)
			(stroke
				(width 0.1)
				(type default)
			)
			(layer "F.Fab")
		)
		(fp_line
			(start -0.12065 0.3048)
			(end -0.67945 0.3048)
			(stroke
				(width 0.1)
				(type default)
			)
			(layer "F.Fab")
		)
		(fp_line
			(start -0.12065 0.2794)
			(end -0.12065 0.3048)
			(stroke
				(width 0.1)
				(type default)
			)
			(layer "F.Fab")
		)
		(fp_line
			(start -0.12065 -0.2794)
			(end 0.12065 -0.2794)
			(stroke
				(width 0.1)
				(type default)
			)
			(layer "F.Fab")
		)
		(fp_line
			(start -0.12065 -0.305054)
			(end -0.12065 -0.2794)
			(stroke
				(width 0.1)
				(type default)
			)
			(layer "F.Fab")
		)
		(fp_line
			(start -0.67945 0.3048)
			(end -0.67945 -0.305054)
			(stroke
				(width 0.1)
				(type default)
			)
			(layer "F.Fab")
		)
		(fp_line
			(start -0.67945 -0.305054)
			(end -0.12065 -0.305054)
			(stroke
				(width 0.1)
				(type default)
			)
			(layer "F.Fab")
		)
		(pad "1" smd circle
			(at -0.40005 0 180)
			(size 0 0)
			(layers "F.Cu" "F.Mask" "F.Paste")
			(net "PVDD18_S5_P1")
		)
		(pad "2" smd circle
			(at 0.40005 0 180)
			(size 0 0)
			(layers "F.Cu" "F.Mask" "F.Paste")
			(net "GND")
		)
	)
)
